FILE_TYPE = CONNECTIVITY;
{Allegro Design Entry HDL 17.4-2019 S026 (4007227) 1/17/2022}
"PAGE_NUMBER" = 179;
0"NC";
END.
